(kicad_pcb
	(version 20260206)
	(generator "pcbnew")
	(generator_version "10.0")
	(general
		(thickness 1.6)
		(legacy_teardrops no)
	)
	(paper "A4")
	(title_block
		(title "Bryce Canyon_F.DPB_16315-1-OCP.brd")
		(comment 1 "Bryce Canyon / footprints 1858-1863 of 2223")
	)
	(layers
		(0 "F.Cu" signal "TOP")
		(4 "In1.Cu" signal "L2GND")
		(6 "In2.Cu" signal "L3")
		(8 "In3.Cu" signal "L4GND")
		(10 "In4.Cu" signal "L5")
		(12 "In5.Cu" signal "L6VCC")
		(14 "In6.Cu" signal "L7VCC")
		(16 "In7.Cu" signal "L8")
		(18 "In8.Cu" signal "L9GND")
		(20 "In9.Cu" signal "L10")
		(22 "In10.Cu" signal "L11GND")
		(2 "B.Cu" signal "BOTTOM")
		(9 "F.Adhes" user "F.Adhesive")
		(11 "B.Adhes" user "B.Adhesive")
		(13 "F.Paste" user "Package Geometry/Pastemask Top")
		(15 "B.Paste" user "Package Geometry/Pastemask Bottom")
		(5 "F.SilkS" user "Ref Des/Silkscreen Top")
		(7 "B.SilkS" user "Ref Des/Silkscreen Bottom")
		(1 "F.Mask" user "Board Geometry/Soldermask Top")
		(3 "B.Mask" user "Board Geometry/Soldermask Bottom")
		(17 "Dwgs.User" user "User.Drawings")
		(19 "Cmts.User" user "User.Comments")
		(21 "Eco1.User" user "User.Eco1")
		(23 "Eco2.User" user "User.Eco2")
		(25 "Edge.Cuts" user "Board Geometry/Outline")
		(27 "Margin" user)
		(31 "F.CrtYd" user "Package Geometry/Place Bound Top")
		(29 "B.CrtYd" user "Package Geometry/Place Bound Bottom")
		(35 "F.Fab" user "Ref Des/Assembly Top")
		(33 "B.Fab" user "Ref Des/Assembly Bottom")
	)
	(footprint ""
		(layer "F.Cu")
		(at 352.3488 -146.4564)
		(property "Reference" "R1096"
			(at 0 0 0)
			(layer "F.SilkS")
			(hide yes)
			(effects
				(font
					(size 1.27 1.27)
				)
			)
		)
		(property "Value" "D001FRL3115F-L-GP"
			(at 3.2766 1.3843 0)
			(unlocked yes)
			(layer "F.Fab")
			(hide yes)
			(effects
				(font
					(size 1.016 1.016)
					(thickness 0.1524)
				)
			)
		)
		(property "Device Type" "RL3115-4PH25"
			(at 3.2766 -0.1397 0)
			(unlocked yes)
			(layer "F.Fab")
			(hide yes)
			(effects
				(font
					(size 1.016 1.016)
					(thickness 0.1524)
				)
			)
		)
		(duplicate_pad_numbers_are_jumpers no)
		(fp_line
			(start -2.0828 -1.778)
			(end -2.0828 -0.4445)
			(stroke
				(width 0.3302)
				(type default)
			)
			(layer "F.SilkS")
		)
		(fp_line
			(start -1.9685 -1.651)
			(end 1.9685 -1.651)
			(stroke
				(width 0.1524)
				(type default)
			)
			(layer "F.SilkS")
		)
		(fp_line
			(start -1.9685 1.651)
			(end -1.9685 -1.651)
			(stroke
				(width 0.1524)
				(type default)
			)
			(layer "F.SilkS")
		)
		(fp_line
			(start -0.5461 -1.778)
			(end -2.0828 -1.778)
			(stroke
				(width 0.3302)
				(type default)
			)
			(layer "F.SilkS")
		)
		(fp_line
			(start 1.9685 -1.651)
			(end 1.9685 1.651)
			(stroke
				(width 0.1524)
				(type default)
			)
			(layer "F.SilkS")
		)
		(fp_line
			(start 1.9685 1.651)
			(end -1.9685 1.651)
			(stroke
				(width 0.1524)
				(type default)
			)
			(layer "F.SilkS")
		)
		(fp_poly
			(pts
				(xy -0.561594 -1.726946) (xy -0.053594 -2.234946) (xy -1.069594 -2.234946)
			)
			(stroke
				(width 0)
				(type default)
			)
			(fill yes)
			(layer "F.SilkS")
		)
		(fp_rect
			(start -1.524 0.7493)
			(end 1.524 -0.7493)
			(stroke
				(width 0)
				(type default)
			)
			(fill no)
			(layer "F.CrtYd")
		)
		(fp_poly
			(pts
				(xy -2.2225 1.905) (xy -2.2225 -1.905) (xy 2.2225 -1.905) (xy 2.2225 -0.7493) (xy -1.524 -0.7493)
				(xy -1.524 0.7493) (xy 1.524 0.7493) (xy 1.524 -0.7366) (xy 2.2225 -0.7366) (xy 2.2225 1.905)
			)
			(stroke
				(width 0)
				(type default)
			)
			(fill no)
			(layer "F.CrtYd")
		)
		(fp_rect
			(start -2.2225 1.905)
			(end 2.2225 -1.905)
			(stroke
				(width 0)
				(type default)
			)
			(fill no)
			(layer "F.Fab")
		)
		(pad "1" smd rect
			(at -0.5715 -0.813562)
			(size 2.286 1.143)
			(layers "F.Cu" "F.Mask" "F.Paste")
			(net "P12V_B")
		)
		(pad "2" smd rect
			(at -0.5715 0.813562)
			(size 2.286 1.143)
			(layers "F.Cu" "F.Mask" "F.Paste")
			(net "MB1_P12V_B_R")
		)
		(pad "3" smd rect
			(at 1.334008 -0.813562)
			(size 0.762 1.143)
			(layers "F.Cu" "F.Mask" "F.Paste")
			(net "MB1_CM_SENSE_R1_P")
		)
		(pad "4" smd rect
			(at 1.334008 0.813562)
			(size 0.762 1.143)
			(layers "F.Cu" "F.Mask" "F.Paste")
			(net "MB1_CM_SENSE_R1_N")
		)
		(zone
			(layer "F.Cu")
			(hatch none 0.5)
			(connect_pads
				(clearance 0)
			)
			(min_thickness 0.25)
			(keepout
				(tracks allowed)
				(vias not_allowed)
				(pads allowed)
				(copperpour not_allowed)
				(footprints allowed)
			)
			(placement
				(enabled no)
				(sheetname "")
			)
			(fill
				(thermal_gap 0.5)
				(thermal_bridge_width 0.5)
				(island_removal_mode 0)
			)
			(polygon
				(pts
					(xy 352.9203 -146.698462) (xy 353.301808 -146.698462) (xy 353.301808 -147.2057) (xy 352.9203 -147.2057)
				)
			)
		)
		(zone
			(layer "F.Cu")
			(hatch none 0.5)
			(connect_pads
				(clearance 0)
			)
			(min_thickness 0.25)
			(keepout
				(tracks not_allowed)
				(vias allowed)
				(pads allowed)
				(copperpour not_allowed)
				(footprints allowed)
			)
			(placement
				(enabled no)
				(sheetname "")
			)
			(fill
				(thermal_gap 0.5)
				(thermal_bridge_width 0.5)
				(island_removal_mode 0)
			)
			(polygon
				(pts
					(xy 352.9203 -146.698462) (xy 353.301808 -146.698462) (xy 353.301808 -147.2057) (xy 352.9203 -147.2057)
				)
			)
		)
		(zone
			(layer "F.Cu")
			(hatch none 0.5)
			(connect_pads
				(clearance 0)
			)
			(min_thickness 0.25)
			(keepout
				(tracks allowed)
				(vias not_allowed)
				(pads allowed)
				(copperpour not_allowed)
				(footprints allowed)
			)
			(placement
				(enabled no)
				(sheetname "")
			)
			(fill
				(thermal_gap 0.5)
				(thermal_bridge_width 0.5)
				(island_removal_mode 0)
			)
			(polygon
				(pts
					(xy 352.9203 -145.7071) (xy 353.301808 -145.7071) (xy 353.301808 -146.214338) (xy 352.9203 -146.214338)
				)
			)
		)
		(zone
			(layer "F.Cu")
			(hatch none 0.5)
			(connect_pads
				(clearance 0)
			)
			(min_thickness 0.25)
			(keepout
				(tracks not_allowed)
				(vias allowed)
				(pads allowed)
				(copperpour not_allowed)
				(footprints allowed)
			)
			(placement
				(enabled no)
				(sheetname "")
			)
			(fill
				(thermal_gap 0.5)
				(thermal_bridge_width 0.5)
				(island_removal_mode 0)
			)
			(polygon
				(pts
					(xy 352.9203 -145.7071) (xy 353.301808 -145.7071) (xy 353.301808 -146.214338) (xy 352.9203 -146.214338)
				)
			)
		)
	)
	(footprint ""
		(layer "F.Cu")
		(at 402.72335 -276.192742 90)
		(property "Reference" "D8"
			(at 0 0 90)
			(layer "F.SilkS")
			(hide yes)
			(effects
				(font
					(size 1.27 1.27)
				)
			)
		)
		(property "Value" "RB551V30-GP"
			(at 0 -6.7818 90)
			(unlocked yes)
			(layer "F.Fab")
			(hide yes)
			(effects
				(font
					(size 1.016 1.016)
					(thickness 0.1524)
				)
			)
		)
		(property "Device Type" "SOD323AKH38"
			(at 0 -8.6868 90)
			(unlocked yes)
			(layer "F.Fab")
			(hide yes)
			(effects
				(font
					(size 1.016 1.016)
					(thickness 0.1524)
				)
			)
		)
		(duplicate_pad_numbers_are_jumpers no)
		(fp_line
			(start 0.889 -1.9304)
			(end 0.889 2.159)
			(stroke
				(width 0.1524)
				(type default)
			)
			(layer "F.SilkS")
		)
		(fp_line
			(start -0.889 -1.9304)
			(end 0.889 -1.9304)
			(stroke
				(width 0.1524)
				(type default)
			)
			(layer "F.SilkS")
		)
		(fp_line
			(start 0.762 2.0574)
			(end -0.762 2.0574)
			(stroke
				(width 0.508)
				(type default)
			)
			(layer "F.SilkS")
		)
		(fp_line
			(start 0.889 2.159)
			(end -0.889 2.159)
			(stroke
				(width 0.1524)
				(type default)
			)
			(layer "F.SilkS")
		)
		(fp_line
			(start -0.889 2.159)
			(end -0.889 -1.9304)
			(stroke
				(width 0.1524)
				(type default)
			)
			(layer "F.SilkS")
		)
		(fp_rect
			(start -1.016 2.3114)
			(end 1.016 -2.0066)
			(stroke
				(width 0)
				(type default)
			)
			(fill no)
			(layer "F.CrtYd")
		)
		(fp_poly
			(pts
				(xy -1.016 -2.0066) (xy 1.016 -2.0066) (xy 1.016 2.3114) (xy -1.016 2.3114)
			)
			(stroke
				(width 0)
				(type default)
			)
			(fill no)
			(layer "F.Fab")
		)
		(pad "A" smd rect
			(at 0 -1.143 90)
			(size 0.5588 1.016)
			(layers "F.Cu" "F.Mask" "F.Paste")
			(net "SW_HDD_R8")
		)
		(pad "K" smd rect
			(at 0 1.143 90)
			(size 0.5588 1.016)
			(layers "F.Cu" "F.Mask" "F.Paste")
			(net "SW_HDD_N8")
		)
	)
	(footprint ""
		(layer "F.Cu")
		(at 441.484512 -158.660592 -90)
		(property "Reference" "C325"
			(at 0 0 270)
			(layer "F.SilkS")
			(hide yes)
			(effects
				(font
					(size 1.27 1.27)
				)
			)
		)
		(property "Value" "SCD01U16V1KX-GP"
			(at -2.8321 -1.7399 270)
			(unlocked yes)
			(layer "F.Fab")
			(hide yes)
			(effects
				(font
					(size 1.016 1.016)
					(thickness 0.1524)
				)
			)
		)
		(property "Device Type" "C0201H13"
			(at -2.8321 -3.2639 270)
			(unlocked yes)
			(layer "F.Fab")
			(hide yes)
			(effects
				(font
					(size 1.016 1.016)
					(thickness 0.1524)
				)
			)
		)
		(duplicate_pad_numbers_are_jumpers no)
		(fp_rect
			(start -0.2794 0.6477)
			(end 0.2794 -0.6477)
			(stroke
				(width 0)
				(type default)
			)
			(fill no)
			(layer "F.CrtYd")
		)
		(fp_rect
			(start -0.2794 0.6477)
			(end 0.2794 -0.6477)
			(stroke
				(width 0)
				(type default)
			)
			(fill no)
			(layer "F.Fab")
		)
		(pad "1" smd custom
			(at 0 -0.2794 270)
			(size 0.0762 0.0762)
			(layers "F.Cu" "F.Mask" "F.Paste")
			(net "SAS_HDD_RX_P22")
			(options
				(clearance outline)
				(anchor circle)
			)
			(primitives
				(gr_poly
					(pts
						(arc
							(start 0.1524 -0.127)
							(mid 0.137521 -0.162921)
							(end 0.1016 -0.1778)
						)
						(arc
							(start -0.1016 -0.1778)
							(mid -0.137521 -0.162921)
							(end -0.1524 -0.127)
						)
						(arc
							(start -0.1524 0.127)
							(mid -0.137521 0.162921)
							(end -0.1016 0.1778)
						)
						(arc
							(start 0.1016 0.1778)
							(mid 0.137521 0.162921)
							(end 0.1524 0.127)
						)
					)
					(width 0)
					(fill yes)
				)
			)
		)
		(pad "2" smd custom
			(at 0 0.2794 270)
			(size 0.0762 0.0762)
			(layers "F.Cu" "F.Mask" "F.Paste")
			(net "PHY_SCC_A_TO_DRV_A_22_DP")
			(options
				(clearance outline)
				(anchor circle)
			)
			(primitives
				(gr_poly
					(pts
						(arc
							(start 0.1524 -0.127)
							(mid 0.137521 -0.162921)
							(end 0.1016 -0.1778)
						)
						(arc
							(start -0.1016 -0.1778)
							(mid -0.137521 -0.162921)
							(end -0.1524 -0.127)
						)
						(arc
							(start -0.1524 0.127)
							(mid -0.137521 0.162921)
							(end -0.1016 0.1778)
						)
						(arc
							(start 0.1016 0.1778)
							(mid 0.137521 0.162921)
							(end 0.1524 0.127)
						)
					)
					(width 0)
					(fill yes)
				)
			)
		)
	)
	(footprint ""
		(layer "F.Cu")
		(at 335.788 -160.735518 180)
		(property "Reference" "R561"
			(at 0 0 180)
			(layer "F.SilkS")
			(hide yes)
			(effects
				(font
					(size 1.27 1.27)
				)
			)
		)
		(property "Value" "0R2J-2-GP"
			(at 0.064008 -3.993896 180)
			(unlocked yes)
			(layer "F.Fab")
			(hide yes)
			(effects
				(font
					(size 1.016 1.016)
					(thickness 0.1524)
				)
			)
		)
		(property "Device Type" "R402H16"
			(at 0.064008 -5.517896 180)
			(unlocked yes)
			(layer "F.Fab")
			(hide yes)
			(effects
				(font
					(size 1.016 1.016)
					(thickness 0.1524)
				)
			)
		)
		(duplicate_pad_numbers_are_jumpers no)
		(fp_line
			(start 0.508 -0.9398)
			(end -0.508 -0.9398)
			(stroke
				(width 0.1524)
				(type default)
			)
			(layer "F.SilkS")
		)
		(fp_line
			(start -0.508 -0.9398)
			(end -0.508 0.9398)
			(stroke
				(width 0.1524)
				(type default)
			)
			(layer "F.SilkS")
		)
		(fp_rect
			(start -0.508 0.9398)
			(end 0.508 -0.9398)
			(stroke
				(width 0)
				(type default)
			)
			(fill no)
			(layer "F.CrtYd")
		)
		(fp_rect
			(start -0.508 0.9398)
			(end 0.508 -0.9398)
			(stroke
				(width 0)
				(type default)
			)
			(fill no)
			(layer "F.Fab")
		)
		(pad "1" smd custom
			(at 0 -0.4445 180)
			(size 0.1397 0.1397)
			(layers "F.Cu" "F.Mask" "F.Paste")
			(net "SW_HDD_G18")
			(options
				(clearance outline)
				(anchor circle)
			)
			(primitives
				(gr_poly
					(pts
						(arc
							(start -0.1778 -0.2794)
							(mid -0.249642 -0.249642)
							(end -0.2794 -0.1778)
						)
						(arc
							(start -0.2794 0.1778)
							(mid -0.249642 0.249642)
							(end -0.1778 0.2794)
						)
						(arc
							(start 0.1778 0.2794)
							(mid 0.249642 0.249642)
							(end 0.2794 0.1778)
						)
						(arc
							(start 0.2794 -0.1778)
							(mid 0.249642 -0.249642)
							(end 0.1778 -0.2794)
						)
					)
					(width 0)
					(fill yes)
				)
			)
		)
		(pad "2" smd custom
			(at 0 0.4445 180)
			(size 0.1397 0.1397)
			(layers "F.Cu" "F.Mask" "F.Paste")
			(net "SW_HDD_R18")
			(options
				(clearance outline)
				(anchor circle)
			)
			(primitives
				(gr_poly
					(pts
						(arc
							(start -0.1778 -0.2794)
							(mid -0.249642 -0.249642)
							(end -0.2794 -0.1778)
						)
						(arc
							(start -0.2794 0.1778)
							(mid -0.249642 0.249642)
							(end -0.1778 0.2794)
						)
						(arc
							(start 0.1778 0.2794)
							(mid 0.249642 0.249642)
							(end 0.2794 0.1778)
						)
						(arc
							(start 0.2794 -0.1778)
							(mid 0.249642 -0.249642)
							(end 0.1778 -0.2794)
						)
					)
					(width 0)
					(fill yes)
				)
			)
		)
	)
	(footprint ""
		(layer "F.Cu")
		(at 339.759036 -33.550352)
		(property "Reference" "R92"
			(at 0 0 0)
			(layer "F.SilkS")
			(hide yes)
			(effects
				(font
					(size 1.27 1.27)
				)
			)
		)
		(property "Value" "4K7R2F-GP"
			(at 0.064008 -3.993896 0)
			(unlocked yes)
			(layer "F.Fab")
			(hide yes)
			(effects
				(font
					(size 1.016 1.016)
					(thickness 0.1524)
				)
			)
		)
		(property "Device Type" "R402H16"
			(at 0.064008 -5.517896 0)
			(unlocked yes)
			(layer "F.Fab")
			(hide yes)
			(effects
				(font
					(size 1.016 1.016)
					(thickness 0.1524)
				)
			)
		)
		(duplicate_pad_numbers_are_jumpers no)
		(fp_line
			(start -0.508 -0.9398)
			(end -0.508 0.9398)
			(stroke
				(width 0.1524)
				(type default)
			)
			(layer "F.SilkS")
		)
		(fp_line
			(start 0.508 -0.9398)
			(end -0.508 -0.9398)
			(stroke
				(width 0.1524)
				(type default)
			)
			(layer "F.SilkS")
		)
		(fp_rect
			(start -0.508 0.9398)
			(end 0.508 -0.9398)
			(stroke
				(width 0)
				(type default)
			)
			(fill no)
			(layer "F.CrtYd")
		)
		(fp_rect
			(start -0.508 0.9398)
			(end 0.508 -0.9398)
			(stroke
				(width 0)
				(type default)
			)
			(fill no)
			(layer "F.Fab")
		)
		(pad "1" smd custom
			(at 0 -0.4445)
			(size 0.1397 0.1397)
			(layers "F.Cu" "F.Mask" "F.Paste")
			(net "P3V3_STBY_B")
			(options
				(clearance outline)
				(anchor circle)
			)
			(primitives
				(gr_poly
					(pts
						(arc
							(start -0.1778 -0.2794)
							(mid -0.249642 -0.249642)
							(end -0.2794 -0.1778)
						)
						(arc
							(start -0.2794 0.1778)
							(mid -0.249642 0.249642)
							(end -0.1778 0.2794)
						)
						(arc
							(start 0.1778 0.2794)
							(mid 0.249642 0.249642)
							(end 0.2794 0.1778)
						)
						(arc
							(start 0.2794 -0.1778)
							(mid 0.249642 -0.249642)
							(end 0.1778 -0.2794)
						)
					)
					(width 0)
					(fill yes)
				)
			)
		)
		(pad "2" smd custom
			(at 0 0.4445)
			(size 0.1397 0.1397)
			(layers "F.Cu" "F.Mask" "F.Paste")
			(net "IO_EXP11_A0")
			(options
				(clearance outline)
				(anchor circle)
			)
			(primitives
				(gr_poly
					(pts
						(arc
							(start -0.1778 -0.2794)
							(mid -0.249642 -0.249642)
							(end -0.2794 -0.1778)
						)
						(arc
							(start -0.2794 0.1778)
							(mid -0.249642 0.249642)
							(end -0.1778 0.2794)
						)
						(arc
							(start 0.1778 0.2794)
							(mid 0.249642 0.249642)
							(end 0.2794 0.1778)
						)
						(arc
							(start 0.2794 -0.1778)
							(mid 0.249642 -0.249642)
							(end 0.1778 -0.2794)
						)
					)
					(width 0)
					(fill yes)
				)
			)
		)
	)
	(footprint ""
		(layer "F.Cu")
		(at 473.593668 -293.892732)
		(property "Reference" "Q299"
			(at 0 0 0)
			(layer "F.SilkS")
			(hide yes)
			(effects
				(font
					(size 1.27 1.27)
				)
			)
		)
		(property "Value" "SSM3K324R-GP"
			(at 0.127 -8.9662 0)
			(unlocked yes)
			(layer "F.Fab")
			(hide yes)
			(effects
				(font
					(size 1.016 1.016)
					(thickness 0.1524)
				)
			)
		)
		(property "Device Type" "SOT23DGS2D4H35"
			(at 0.127 -10.4902 0)
			(unlocked yes)
			(layer "F.Fab")
			(hide yes)
			(effects
				(font
					(size 1.016 1.016)
					(thickness 0.1524)
				)
			)
		)
		(duplicate_pad_numbers_are_jumpers no)
		(fp_line
			(start -1.651 -1.778)
			(end -1.651 1.778)
			(stroke
				(width 0.1524)
				(type default)
			)
			(layer "F.SilkS")
		)
		(fp_line
			(start -1.651 1.778)
			(end 1.651 1.778)
			(stroke
				(width 0.1524)
				(type default)
			)
			(layer "F.SilkS")
		)
		(fp_line
			(start 1.651 -1.778)
			(end -1.651 -1.778)
			(stroke
				(width 0.1524)
				(type default)
			)
			(layer "F.SilkS")
		)
		(fp_line
			(start 1.651 1.778)
			(end 1.651 -1.778)
			(stroke
				(width 0.1524)
				(type default)
			)
			(layer "F.SilkS")
		)
		(fp_poly
			(pts
				(xy -1.778 1.8796) (xy -1.778 -1.8796) (xy 1.778 -1.8796) (xy 1.778 1.8796)
			)
			(stroke
				(width 0)
				(type default)
			)
			(fill no)
			(layer "F.CrtYd")
		)
		(fp_poly
			(pts
				(xy -1.778 1.8796) (xy -1.778 -1.8796) (xy 1.778 -1.8796) (xy 1.778 1.8796)
			)
			(stroke
				(width 0)
				(type default)
			)
			(fill no)
			(layer "F.Fab")
		)
		(pad "D" smd custom
			(at 0 -0.9525)
			(size 0.1905 0.1905)
			(layers "F.Cu" "F.Mask" "F.Paste")
			(net "DRV_ACT_35_N")
			(options
				(clearance outline)
				(anchor circle)
			)
			(primitives
				(gr_poly
					(pts
						(arc
							(start -0.1778 0.5715)
							(mid -0.321484 0.511984)
							(end -0.381 0.3683)
						)
						(arc
							(start -0.381 -0.3683)
							(mid -0.321484 -0.511984)
							(end -0.1778 -0.5715)
						)
						(arc
							(start 0.1778 -0.5715)
							(mid 0.321484 -0.511984)
							(end 0.381 -0.3683)
						)
						(arc
							(start 0.381 0.3683)
							(mid 0.321484 0.511984)
							(end 0.1778 0.5715)
						)
					)
					(width 0)
					(fill yes)
				)
			)
		)
		(pad "G" smd custom
			(at -0.98425 0.9525)
			(size 0.1905 0.1905)
			(layers "F.Cu" "F.Mask" "F.Paste")
			(net "DRIVE_B_35_ACT")
			(options
				(clearance outline)
				(anchor circle)
			)
			(primitives
				(gr_poly
					(pts
						(arc
							(start -0.1778 0.5715)
							(mid -0.321484 0.511984)
							(end -0.381 0.3683)
						)
						(arc
							(start -0.381 -0.3683)
							(mid -0.321484 -0.511984)
							(end -0.1778 -0.5715)
						)
						(arc
							(start 0.1778 -0.5715)
							(mid 0.321484 -0.511984)
							(end 0.381 -0.3683)
						)
						(arc
							(start 0.381 0.3683)
							(mid 0.321484 0.511984)
							(end 0.1778 0.5715)
						)
					)
					(width 0)
					(fill yes)
				)
			)
		)
		(pad "S" smd custom
			(at 0.98425 0.9525)
			(size 0.1905 0.1905)
			(layers "F.Cu" "F.Mask" "F.Paste")
			(net "GND")
			(options
				(clearance outline)
				(anchor circle)
			)
			(primitives
				(gr_poly
					(pts
						(arc
							(start -0.1778 0.5715)
							(mid -0.321484 0.511984)
							(end -0.381 0.3683)
						)
						(arc
							(start -0.381 -0.3683)
							(mid -0.321484 -0.511984)
							(end -0.1778 -0.5715)
						)
						(arc
							(start 0.1778 -0.5715)
							(mid 0.321484 -0.511984)
							(end 0.381 -0.3683)
						)
						(arc
							(start 0.381 0.3683)
							(mid 0.321484 0.511984)
							(end 0.1778 0.5715)
						)
					)
					(width 0)
					(fill yes)
				)
			)
		)
	)
)
